(kicad_pcb
	(version 20260206)
	(generator "pcbnew")
	(generator_version "10.0")
	(general
		(thickness 1.6)
		(legacy_teardrops no)
	)
	(paper "A4")
	(title_block
		(title "Bryce Canyon_IOM_M2_16342-2_OCP.brd")
		(comment 1 "Bryce Canyon / footprints 553-559 of 1146")
	)
	(layers
		(0 "F.Cu" signal "TOP")
		(4 "In1.Cu" signal "L2GND")
		(6 "In2.Cu" signal "L3")
		(8 "In3.Cu" signal "L4VCC")
		(10 "In4.Cu" signal "L5VCC")
		(12 "In5.Cu" signal "L6")
		(14 "In6.Cu" signal "L7GND")
		(2 "B.Cu" signal "BOTTOM")
		(9 "F.Adhes" user "F.Adhesive")
		(11 "B.Adhes" user "B.Adhesive")
		(13 "F.Paste" user "Package Geometry/Pastemask Top")
		(15 "B.Paste" user "Package Geometry/Pastemask Bottom")
		(5 "F.SilkS" user "Ref Des/Silkscreen Top")
		(7 "B.SilkS" user "Ref Des/Silkscreen Bottom")
		(1 "F.Mask" user "Board Geometry/Soldermask Top")
		(3 "B.Mask" user "Board Geometry/Soldermask Bottom")
		(17 "Dwgs.User" user "User.Drawings")
		(19 "Cmts.User" user "User.Comments")
		(21 "Eco1.User" user "User.Eco1")
		(23 "Eco2.User" user "User.Eco2")
		(25 "Edge.Cuts" user "Board Geometry/Outline")
		(27 "Margin" user)
		(31 "F.CrtYd" user "Package Geometry/Place Bound Top")
		(29 "B.CrtYd" user "Package Geometry/Place Bound Bottom")
		(35 "F.Fab" user "Ref Des/Assembly Top")
		(33 "B.Fab" user "Ref Des/Assembly Bottom")
	)
	(footprint ""
		(layer "F.Cu")
		(at 206.000096 -6.199886)
		(property "Reference" "LED3"
			(at 0 0 0)
			(layer "F.SilkS")
			(hide yes)
			(effects
				(font
					(size 1.27 1.27)
				)
			)
		)
		(property "Value" "LED-BY-14-GP"
			(at -4.7752 -2.1844 0)
			(unlocked yes)
			(layer "F.Fab")
			(hide yes)
			(effects
				(font
					(size 1.016 1.016)
					(thickness 0.1524)
				)
			)
		)
		(property "Device Type" "LED-100-3PH206"
			(at -4.7752 -3.7084 0)
			(unlocked yes)
			(layer "F.Fab")
			(hide yes)
			(effects
				(font
					(size 1.016 1.016)
					(thickness 0.1524)
				)
			)
		)
		(duplicate_pad_numbers_are_jumpers no)
		(fp_line
			(start -3.7592 -1.524)
			(end 3.7592 -1.524)
			(stroke
				(width 0.1524)
				(type default)
			)
			(layer "F.SilkS")
		)
		(fp_line
			(start -3.7592 8.0264)
			(end -3.7592 -1.524)
			(stroke
				(width 0.1524)
				(type default)
			)
			(layer "F.SilkS")
		)
		(fp_line
			(start -1.75387 1.04394)
			(end -1.75387 3.63474)
			(stroke
				(width 0.1524)
				(type default)
			)
			(layer "F.SilkS")
		)
		(fp_line
			(start -1.75387 2.33934)
			(end -3.45567 2.33934)
			(stroke
				(width 0.1524)
				(type default)
			)
			(layer "F.SilkS")
		)
		(fp_line
			(start -1.75387 3.63474)
			(end -0.45847 2.33934)
			(stroke
				(width 0.1524)
				(type default)
			)
			(layer "F.SilkS")
		)
		(fp_line
			(start -0.45847 2.33934)
			(end -1.75387 1.04394)
			(stroke
				(width 0.1524)
				(type default)
			)
			(layer "F.SilkS")
		)
		(fp_line
			(start -0.45847 2.33934)
			(end 0.58293 2.33934)
			(stroke
				(width 0.1524)
				(type default)
			)
			(layer "F.SilkS")
		)
		(fp_line
			(start -0.45847 3.05054)
			(end -0.45847 1.42494)
			(stroke
				(width 0.1524)
				(type default)
			)
			(layer "F.SilkS")
		)
		(fp_line
			(start 0.58293 2.33934)
			(end 1.87833 1.04394)
			(stroke
				(width 0.1524)
				(type default)
			)
			(layer "F.SilkS")
		)
		(fp_line
			(start 0.58293 3.05054)
			(end 0.58293 1.42494)
			(stroke
				(width 0.1524)
				(type default)
			)
			(layer "F.SilkS")
		)
		(fp_line
			(start 1.87833 1.04394)
			(end 1.87833 3.63474)
			(stroke
				(width 0.1524)
				(type default)
			)
			(layer "F.SilkS")
		)
		(fp_line
			(start 1.87833 2.33934)
			(end 2.81813 2.33934)
			(stroke
				(width 0.1524)
				(type default)
			)
			(layer "F.SilkS")
		)
		(fp_line
			(start 1.87833 3.63474)
			(end 0.58293 2.33934)
			(stroke
				(width 0.1524)
				(type default)
			)
			(layer "F.SilkS")
		)
		(fp_line
			(start 3.7592 -1.524)
			(end 3.7592 8.0264)
			(stroke
				(width 0.1524)
				(type default)
			)
			(layer "F.SilkS")
		)
		(fp_line
			(start 3.7592 8.0264)
			(end -3.7592 8.0264)
			(stroke
				(width 0.1524)
				(type default)
			)
			(layer "F.SilkS")
		)
		(fp_circle
			(center -2.54 0)
			(end -1.5494 0)
			(stroke
				(width 0.3048)
				(type default)
			)
			(fill no)
			(layer "F.SilkS")
		)
		(fp_circle
			(center 0 0)
			(end 0.9906 0)
			(stroke
				(width 0.3048)
				(type default)
			)
			(fill no)
			(layer "F.SilkS")
		)
		(fp_circle
			(center 2.54 0)
			(end 3.5306 0)
			(stroke
				(width 0.3048)
				(type default)
			)
			(fill no)
			(layer "F.SilkS")
		)
		(fp_rect
			(start -3.5052 7.7724)
			(end 3.5052 -1.27)
			(stroke
				(width 0)
				(type default)
			)
			(fill no)
			(layer "F.CrtYd")
		)
		(fp_poly
			(pts
				(xy -4.0132 8.2804) (xy -4.0132 -1.778) (xy -3.5052 -1.778) (xy -3.5052 7.7724) (xy 3.5052 7.7724)
				(xy 3.5052 -1.27) (xy -3.50012 -1.27) (xy -3.50012 -1.778) (xy 4.0132 -1.778) (xy 4.0132 8.2804)
			)
			(stroke
				(width 0)
				(type default)
			)
			(fill no)
			(layer "F.CrtYd")
		)
		(fp_rect
			(start -4.0132 8.2804)
			(end 4.0132 -1.778)
			(stroke
				(width 0)
				(type default)
			)
			(fill no)
			(layer "F.Fab")
		)
		(pad "1" thru_hole circle
			(at -2.54 0)
			(size 1.27 1.27)
			(drill 0.889)
			(layers "*.Cu" "*.Mask")
			(remove_unused_layers no)
			(net "ML_PWR_BLUE_LED_R")
			(clearance 0.1651)
			(thermal_gap 0.1651)
		)
		(pad "2" thru_hole circle
			(at 0 0)
			(size 1.27 1.27)
			(drill 0.889)
			(layers "*.Cu" "*.Mask")
			(remove_unused_layers no)
			(net "GND")
			(clearance 0.1651)
			(thermal_gap 0.1651)
		)
		(pad "3" thru_hole circle
			(at 2.54 0)
			(size 1.27 1.27)
			(drill 0.889)
			(layers "*.Cu" "*.Mask")
			(remove_unused_layers no)
			(net "ML_PWR_YELLOW_LED_R")
			(clearance 0.1651)
			(thermal_gap 0.1651)
		)
	)
	(footprint ""
		(layer "F.Cu")
		(at 147.585938 -9.450578 -90)
		(property "Reference" "R521"
			(at 0 0 270)
			(layer "F.SilkS")
			(hide yes)
			(effects
				(font
					(size 1.27 1.27)
				)
			)
		)
		(property "Value" "15KR2F-GP"
			(at 0.064008 -3.993896 270)
			(unlocked yes)
			(layer "F.Fab")
			(hide yes)
			(effects
				(font
					(size 1.016 1.016)
					(thickness 0.1524)
				)
			)
		)
		(property "Device Type" "R402H16"
			(at 0.064008 -5.517896 270)
			(unlocked yes)
			(layer "F.Fab")
			(hide yes)
			(effects
				(font
					(size 1.016 1.016)
					(thickness 0.1524)
				)
			)
		)
		(duplicate_pad_numbers_are_jumpers no)
		(fp_line
			(start -0.508 -0.9398)
			(end -0.508 0.9398)
			(stroke
				(width 0.1524)
				(type default)
			)
			(layer "F.SilkS")
		)
		(fp_line
			(start 0.508 -0.9398)
			(end -0.508 -0.9398)
			(stroke
				(width 0.1524)
				(type default)
			)
			(layer "F.SilkS")
		)
		(fp_rect
			(start -0.508 0.9398)
			(end 0.508 -0.9398)
			(stroke
				(width 0)
				(type default)
			)
			(fill no)
			(layer "F.CrtYd")
		)
		(fp_rect
			(start -0.508 0.9398)
			(end 0.508 -0.9398)
			(stroke
				(width 0)
				(type default)
			)
			(fill no)
			(layer "F.Fab")
		)
		(pad "1" smd custom
			(at 0 -0.4445 270)
			(size 0.1397 0.1397)
			(layers "F.Cu" "F.Mask" "F.Paste")
			(net "PWRGD_P1V8_STBY")
			(options
				(clearance outline)
				(anchor circle)
			)
			(primitives
				(gr_poly
					(pts
						(arc
							(start -0.1778 -0.2794)
							(mid -0.249642 -0.249642)
							(end -0.2794 -0.1778)
						)
						(arc
							(start -0.2794 0.1778)
							(mid -0.249642 0.249642)
							(end -0.1778 0.2794)
						)
						(arc
							(start 0.1778 0.2794)
							(mid 0.249642 0.249642)
							(end 0.2794 0.1778)
						)
						(arc
							(start 0.2794 -0.1778)
							(mid 0.249642 -0.249642)
							(end 0.1778 -0.2794)
						)
					)
					(width 0)
					(fill yes)
				)
			)
		)
		(pad "2" smd custom
			(at 0 0.4445 270)
			(size 0.1397 0.1397)
			(layers "F.Cu" "F.Mask" "F.Paste")
			(net "GND")
			(options
				(clearance outline)
				(anchor circle)
			)
			(primitives
				(gr_poly
					(pts
						(arc
							(start -0.1778 -0.2794)
							(mid -0.249642 -0.249642)
							(end -0.2794 -0.1778)
						)
						(arc
							(start -0.2794 0.1778)
							(mid -0.249642 0.249642)
							(end -0.1778 0.2794)
						)
						(arc
							(start 0.1778 0.2794)
							(mid 0.249642 0.249642)
							(end 0.2794 0.1778)
						)
						(arc
							(start 0.2794 -0.1778)
							(mid 0.249642 -0.249642)
							(end 0.1778 -0.2794)
						)
					)
					(width 0)
					(fill yes)
				)
			)
		)
	)
	(footprint ""
		(layer "F.Cu")
		(at 79.99984 -120.000014)
		(property "Reference" ""
			(at 0 0 0)
			(layer "F.SilkS")
			(hide yes)
			(effects
				(font
					(size 1.27 1.27)
				)
			)
		)
		(property "Value" "*"
			(at -6.38175 0.19685 0)
			(unlocked yes)
			(layer "F.Fab")
			(hide yes)
			(effects
				(font
					(size 1.016 1.016)
					(thickness 0.1524)
				)
			)
		)
		(duplicate_pad_numbers_are_jumpers no)
		(fp_poly
			(pts
				(arc
					(start 5.0673 0)
					(mid -5.0673 0)
					(end 5.0673 0)
				)
			)
			(stroke
				(width 0)
				(type default)
			)
			(fill no)
			(layer "B.CrtYd")
		)
		(fp_poly
			(pts
				(arc
					(start 5.0673 0)
					(mid -5.0673 0)
					(end 5.0673 0)
				)
			)
			(stroke
				(width 0)
				(type default)
			)
			(fill no)
			(layer "F.CrtYd")
		)
		(fp_poly
			(pts
				(arc
					(start 5.0673 0)
					(mid -5.0673 0)
					(end 5.0673 0)
				)
			)
			(stroke
				(width 0)
				(type default)
			)
			(fill no)
			(layer "B.Fab")
		)
		(fp_poly
			(pts
				(arc
					(start 5.0673 0)
					(mid -5.0673 0)
					(end 5.0673 0)
				)
			)
			(stroke
				(width 0)
				(type default)
			)
			(fill no)
			(layer "F.Fab")
		)
		(pad "1" thru_hole circle
			(at 0 0)
			(size 9.525 9.525)
			(drill 3.5052)
			(layers "*.Cu" "*.Mask")
			(remove_unused_layers no)
			(net "Net_40")
			(clearance -2.5019)
			(thermal_gap 0.3048)
			(padstack
				(mode front_inner_back)
				(layer "Inner"
					(shape circle)
					(size 3.9116 3.9116)
					(clearance 0.3048)
				)
				(layer "B.Cu"
					(shape circle)
					(size 9.525 9.525)
					(clearance -2.5019)
				)
			)
		)
	)
	(footprint ""
		(layer "F.Cu")
		(at 10.529316 -172.6565 -90)
		(property "Reference" "R535"
			(at 0 0 270)
			(layer "F.SilkS")
			(hide yes)
			(effects
				(font
					(size 1.27 1.27)
				)
			)
		)
		(property "Value" "0R2J-2-GP"
			(at 0.064008 -3.993896 270)
			(unlocked yes)
			(layer "F.Fab")
			(hide yes)
			(effects
				(font
					(size 1.016 1.016)
					(thickness 0.1524)
				)
			)
		)
		(property "Device Type" "R402H16"
			(at 0.064008 -5.517896 270)
			(unlocked yes)
			(layer "F.Fab")
			(hide yes)
			(effects
				(font
					(size 1.016 1.016)
					(thickness 0.1524)
				)
			)
		)
		(duplicate_pad_numbers_are_jumpers no)
		(fp_line
			(start -0.508 -0.9398)
			(end -0.508 0.9398)
			(stroke
				(width 0.1524)
				(type default)
			)
			(layer "F.SilkS")
		)
		(fp_line
			(start 0.508 -0.9398)
			(end -0.508 -0.9398)
			(stroke
				(width 0.1524)
				(type default)
			)
			(layer "F.SilkS")
		)
		(fp_rect
			(start -0.508 0.9398)
			(end 0.508 -0.9398)
			(stroke
				(width 0)
				(type default)
			)
			(fill no)
			(layer "F.CrtYd")
		)
		(fp_rect
			(start -0.508 0.9398)
			(end 0.508 -0.9398)
			(stroke
				(width 0)
				(type default)
			)
			(fill no)
			(layer "F.Fab")
		)
		(pad "1" smd custom
			(at 0 -0.4445 270)
			(size 0.1397 0.1397)
			(layers "F.Cu" "F.Mask" "F.Paste")
			(net "TPS74801_P1V2_STBY_EN")
			(options
				(clearance outline)
				(anchor circle)
			)
			(primitives
				(gr_poly
					(pts
						(arc
							(start -0.1778 -0.2794)
							(mid -0.249642 -0.249642)
							(end -0.2794 -0.1778)
						)
						(arc
							(start -0.2794 0.1778)
							(mid -0.249642 0.249642)
							(end -0.1778 0.2794)
						)
						(arc
							(start 0.1778 0.2794)
							(mid 0.249642 0.249642)
							(end 0.2794 0.1778)
						)
						(arc
							(start 0.2794 -0.1778)
							(mid 0.249642 -0.249642)
							(end 0.1778 -0.2794)
						)
					)
					(width 0)
					(fill yes)
				)
			)
		)
		(pad "2" smd custom
			(at 0 0.4445 270)
			(size 0.1397 0.1397)
			(layers "F.Cu" "F.Mask" "F.Paste")
			(net "PWRGD_P1V8_STBY")
			(options
				(clearance outline)
				(anchor circle)
			)
			(primitives
				(gr_poly
					(pts
						(arc
							(start -0.1778 -0.2794)
							(mid -0.249642 -0.249642)
							(end -0.2794 -0.1778)
						)
						(arc
							(start -0.2794 0.1778)
							(mid -0.249642 0.249642)
							(end -0.1778 0.2794)
						)
						(arc
							(start 0.1778 0.2794)
							(mid 0.249642 0.249642)
							(end 0.2794 0.1778)
						)
						(arc
							(start 0.2794 -0.1778)
							(mid 0.249642 -0.249642)
							(end 0.1778 -0.2794)
						)
					)
					(width 0)
					(fill yes)
				)
			)
		)
	)
	(footprint ""
		(layer "F.Cu")
		(at 62.214252 -134.239254 -90)
		(property "Reference" "R343"
			(at 0 0 270)
			(layer "F.SilkS")
			(hide yes)
			(effects
				(font
					(size 1.27 1.27)
				)
			)
		)
		(property "Value" "0R2J-2-GP"
			(at 0.064008 -3.993896 270)
			(unlocked yes)
			(layer "F.Fab")
			(hide yes)
			(effects
				(font
					(size 1.016 1.016)
					(thickness 0.1524)
				)
			)
		)
		(property "Device Type" "R402H16"
			(at 0.064008 -5.517896 270)
			(unlocked yes)
			(layer "F.Fab")
			(hide yes)
			(effects
				(font
					(size 1.016 1.016)
					(thickness 0.1524)
				)
			)
		)
		(duplicate_pad_numbers_are_jumpers no)
		(fp_line
			(start -0.508 -0.9398)
			(end -0.508 0.9398)
			(stroke
				(width 0.1524)
				(type default)
			)
			(layer "F.SilkS")
		)
		(fp_line
			(start 0.508 -0.9398)
			(end -0.508 -0.9398)
			(stroke
				(width 0.1524)
				(type default)
			)
			(layer "F.SilkS")
		)
		(fp_rect
			(start -0.508 0.9398)
			(end 0.508 -0.9398)
			(stroke
				(width 0)
				(type default)
			)
			(fill no)
			(layer "F.CrtYd")
		)
		(fp_rect
			(start -0.508 0.9398)
			(end 0.508 -0.9398)
			(stroke
				(width 0)
				(type default)
			)
			(fill no)
			(layer "F.Fab")
		)
		(pad "1" smd custom
			(at 0 -0.4445 270)
			(size 0.1397 0.1397)
			(layers "F.Cu" "F.Mask" "F.Paste")
			(net "COMP_SPARE_0")
			(options
				(clearance outline)
				(anchor circle)
			)
			(primitives
				(gr_poly
					(pts
						(arc
							(start -0.1778 -0.2794)
							(mid -0.249642 -0.249642)
							(end -0.2794 -0.1778)
						)
						(arc
							(start -0.2794 0.1778)
							(mid -0.249642 0.249642)
							(end -0.1778 0.2794)
						)
						(arc
							(start 0.1778 0.2794)
							(mid 0.249642 0.249642)
							(end 0.2794 0.1778)
						)
						(arc
							(start 0.2794 -0.1778)
							(mid 0.249642 -0.249642)
							(end 0.1778 -0.2794)
						)
					)
					(width 0)
					(fill yes)
				)
			)
		)
		(pad "2" smd custom
			(at 0 0.4445 270)
			(size 0.1397 0.1397)
			(layers "F.Cu" "F.Mask" "F.Paste")
			(net "COMP_SPARE_0_R")
			(options
				(clearance outline)
				(anchor circle)
			)
			(primitives
				(gr_poly
					(pts
						(arc
							(start -0.1778 -0.2794)
							(mid -0.249642 -0.249642)
							(end -0.2794 -0.1778)
						)
						(arc
							(start -0.2794 0.1778)
							(mid -0.249642 0.249642)
							(end -0.1778 0.2794)
						)
						(arc
							(start 0.1778 0.2794)
							(mid 0.249642 0.249642)
							(end 0.2794 0.1778)
						)
						(arc
							(start 0.2794 -0.1778)
							(mid 0.249642 -0.249642)
							(end 0.1778 -0.2794)
						)
					)
					(width 0)
					(fill yes)
				)
			)
		)
	)
	(footprint ""
		(layer "F.Cu")
		(at 81.788 -163.5252)
		(property "Reference" "C242"
			(at 0 0 0)
			(layer "F.SilkS")
			(hide yes)
			(effects
				(font
					(size 1.27 1.27)
				)
			)
		)
		(property "Value" "SCD1U16V2KX-3GP"
			(at 1.1811 -2.7051 0)
			(unlocked yes)
			(layer "F.Fab")
			(hide yes)
			(effects
				(font
					(size 1.016 1.016)
					(thickness 0.1524)
				)
			)
		)
		(property "Device Type" "C402H22"
			(at 1.1811 -4.2291 0)
			(unlocked yes)
			(layer "F.Fab")
			(hide yes)
			(effects
				(font
					(size 1.016 1.016)
					(thickness 0.1524)
				)
			)
		)
		(duplicate_pad_numbers_are_jumpers no)
		(fp_rect
			(start -0.4318 0.9525)
			(end 0.4318 -0.9525)
			(stroke
				(width 0)
				(type default)
			)
			(fill no)
			(layer "F.CrtYd")
		)
		(fp_rect
			(start -0.4318 0.9525)
			(end 0.4318 -0.9525)
			(stroke
				(width 0)
				(type default)
			)
			(fill no)
			(layer "F.Fab")
		)
		(pad "1" smd custom
			(at 0 -0.4445)
			(size 0.1524 0.1524)
			(layers "F.Cu" "F.Mask" "F.Paste")
			(net "P1V8_STBY")
			(options
				(clearance outline)
				(anchor circle)
			)
			(primitives
				(gr_poly
					(pts
						(arc
							(start 0.3048 -0.2032)
							(mid 0.275042 -0.275042)
							(end 0.2032 -0.3048)
						)
						(arc
							(start -0.2032 -0.3048)
							(mid -0.275042 -0.275042)
							(end -0.3048 -0.2032)
						)
						(arc
							(start -0.3048 0.2032)
							(mid -0.275042 0.275042)
							(end -0.2032 0.3048)
						)
						(arc
							(start 0.2032 0.3048)
							(mid 0.275042 0.275042)
							(end 0.3048 0.2032)
						)
					)
					(width 0)
					(fill yes)
				)
			)
		)
		(pad "2" smd custom
			(at 0 0.4445)
			(size 0.1524 0.1524)
			(layers "F.Cu" "F.Mask" "F.Paste")
			(net "GND")
			(options
				(clearance outline)
				(anchor circle)
			)
			(primitives
				(gr_poly
					(pts
						(arc
							(start 0.3048 -0.2032)
							(mid 0.275042 -0.275042)
							(end 0.2032 -0.3048)
						)
						(arc
							(start -0.2032 -0.3048)
							(mid -0.275042 -0.275042)
							(end -0.3048 -0.2032)
						)
						(arc
							(start -0.3048 0.2032)
							(mid -0.275042 0.275042)
							(end -0.2032 0.3048)
						)
						(arc
							(start 0.2032 0.3048)
							(mid 0.275042 0.275042)
							(end 0.3048 0.2032)
						)
					)
					(width 0)
					(fill yes)
				)
			)
		)
	)
	(footprint ""
		(layer "F.Cu")
		(at 99.283774 -158.05531 90)
		(property "Reference" "R26"
			(at 0 0 90)
			(layer "F.SilkS")
			(hide yes)
			(effects
				(font
					(size 1.27 1.27)
				)
			)
		)
		(property "Value" "0R2J-2-GP"
			(at 0.064008 -3.993896 90)
			(unlocked yes)
			(layer "F.Fab")
			(hide yes)
			(effects
				(font
					(size 1.016 1.016)
					(thickness 0.1524)
				)
			)
		)
		(property "Device Type" "R402H16"
			(at 0.064008 -5.517896 90)
			(unlocked yes)
			(layer "F.Fab")
			(hide yes)
			(effects
				(font
					(size 1.016 1.016)
					(thickness 0.1524)
				)
			)
		)
		(duplicate_pad_numbers_are_jumpers no)
		(fp_line
			(start 0.508 -0.9398)
			(end -0.508 -0.9398)
			(stroke
				(width 0.1524)
				(type default)
			)
			(layer "F.SilkS")
		)
		(fp_line
			(start -0.508 -0.9398)
			(end -0.508 0.9398)
			(stroke
				(width 0.1524)
				(type default)
			)
			(layer "F.SilkS")
		)
		(fp_rect
			(start -0.508 0.9398)
			(end 0.508 -0.9398)
			(stroke
				(width 0)
				(type default)
			)
			(fill no)
			(layer "F.CrtYd")
		)
		(fp_rect
			(start -0.508 0.9398)
			(end 0.508 -0.9398)
			(stroke
				(width 0)
				(type default)
			)
			(fill no)
			(layer "F.Fab")
		)
		(pad "1" smd custom
			(at 0 -0.4445 90)
			(size 0.1397 0.1397)
			(layers "F.Cu" "F.Mask" "F.Paste")
			(net "USB_RESET_N")
			(options
				(clearance outline)
				(anchor circle)
			)
			(primitives
				(gr_poly
					(pts
						(arc
							(start -0.1778 -0.2794)
							(mid -0.249642 -0.249642)
							(end -0.2794 -0.1778)
						)
						(arc
							(start -0.2794 0.1778)
							(mid -0.249642 0.249642)
							(end -0.1778 0.2794)
						)
						(arc
							(start 0.1778 0.2794)
							(mid 0.249642 0.249642)
							(end 0.2794 0.1778)
						)
						(arc
							(start 0.2794 -0.1778)
							(mid 0.249642 -0.249642)
							(end 0.1778 -0.2794)
						)
					)
					(width 0)
					(fill yes)
				)
			)
		)
		(pad "2" smd custom
			(at 0 0.4445 90)
			(size 0.1397 0.1397)
			(layers "F.Cu" "F.Mask" "F.Paste")
			(net "PCIE_COMP_TO_IOM_RST_4")
			(options
				(clearance outline)
				(anchor circle)
			)
			(primitives
				(gr_poly
					(pts
						(arc
							(start -0.1778 -0.2794)
							(mid -0.249642 -0.249642)
							(end -0.2794 -0.1778)
						)
						(arc
							(start -0.2794 0.1778)
							(mid -0.249642 0.249642)
							(end -0.1778 0.2794)
						)
						(arc
							(start 0.1778 0.2794)
							(mid 0.249642 0.249642)
							(end 0.2794 0.1778)
						)
						(arc
							(start 0.2794 -0.1778)
							(mid 0.249642 -0.249642)
							(end 0.1778 -0.2794)
						)
					)
					(width 0)
					(fill yes)
				)
			)
		)
	)
)
